# S9S_MB_2U (Grand Teton) — schematic netlist excerpt (pin names and nets, part order shuffled) for the footprints in the layout excerpt that follows; sources: Cadence DE-HDL packaged netlist, KiCad conversion of 03242023_DA0F0TMBIJ0_F0T_Motherboard_J_brd_V01_OCP.brd

R859  Q_RES  0 5% CHIP  pkg 0402LF  page 128 : A = RST_CPU1_DRAM_AB_N ; B = RST_CPU1_DRAM_AB_PLD_N
R992  Q_RES  2K 1% EMPTY  pkg 0402LF  page 219 : A = PWRGD_CPU0_LVC1_R ; B = GND

(kicad_pcb
	(version 20260206)
	(generator "pcbnew")
	(generator_version "10.0")
	(general
		(thickness 1.6)
		(legacy_teardrops no)
	)
	(paper "A4")
	(title_block
		(title "03242023_DA0F0TMBIJ0_F0T_Motherboard_J_brd_V01_OCP.brd")
		(comment 1 "Grand Teton / footprints 4060-4061 of 6105")
	)
	(layers
		(0 "F.Cu" signal "TOP")
		(4 "In1.Cu" signal "GND")
		(6 "In2.Cu" signal "IN1")
		(8 "In3.Cu" signal "GND1")
		(10 "In4.Cu" signal "IN2")
		(12 "In5.Cu" signal "GND2")
		(14 "In6.Cu" signal "IN3")
		(16 "In7.Cu" signal "GND3")
		(18 "In8.Cu" signal "VCC")
		(20 "In9.Cu" signal "VCC1")
		(22 "In10.Cu" signal "GND4")
		(24 "In11.Cu" signal "IN4")
		(26 "In12.Cu" signal "GND5")
		(28 "In13.Cu" signal "IN5")
		(30 "In14.Cu" signal "GND6")
		(32 "In15.Cu" signal "IN6")
		(34 "In16.Cu" signal "GND7")
		(2 "B.Cu" signal "BOTTOM")
		(9 "F.Adhes" user "F.Adhesive")
		(11 "B.Adhes" user "B.Adhesive")
		(13 "F.Paste" user "Package Geometry/Pastemask Top")
		(15 "B.Paste" user "Package Geometry/Pastemask Bottom")
		(5 "F.SilkS" user "Ref Des/Silkscreen Top")
		(7 "B.SilkS" user "Ref Des/Silkscreen Bottom")
		(1 "F.Mask" user "Board Geometry/Soldermask Top")
		(3 "B.Mask" user "Board Geometry/Soldermask Bottom")
		(17 "Dwgs.User" user "User.Drawings")
		(19 "Cmts.User" user "User.Comments")
		(21 "Eco1.User" user "User.Eco1")
		(23 "Eco2.User" user "User.Eco2")
		(25 "Edge.Cuts" user "Board Geometry/Outline")
		(27 "Margin" user)
		(31 "F.CrtYd" user "Package Geometry/Place Bound Top")
		(29 "B.CrtYd" user "Package Geometry/Place Bound Bottom")
		(35 "F.Fab" user "Ref Des/Assembly Top")
		(33 "B.Fab" user "Ref Des/Assembly Bottom")
	)
	(footprint ""
		(layer "F.Cu")
		(at 120.438926 -119.810784 -90)
		(property "Reference" "R859"
			(at 0 0 270)
			(layer "F.SilkS")
			(hide yes)
			(effects
				(font
					(size 1.27 1.27)
				)
			)
		)
		(property "Value" ""
			(at 0 0 270)
			(layer "F.Fab")
			(effects
				(font
					(size 1.27 1.27)
				)
			)
		)
		(duplicate_pad_numbers_are_jumpers no)
		(fp_line
			(start -0.7874 0.4064)
			(end -0.7874 -0.4064)
			(stroke
				(width 0.1524)
				(type default)
			)
			(layer "F.SilkS")
		)
		(fp_line
			(start 0.7874 0.4064)
			(end -0.7874 0.4064)
			(stroke
				(width 0.1524)
				(type default)
			)
			(layer "F.SilkS")
		)
		(fp_line
			(start -0.7874 -0.4064)
			(end 0.7874 -0.4064)
			(stroke
				(width 0.1524)
				(type default)
			)
			(layer "F.SilkS")
		)
		(fp_line
			(start 0.7874 -0.4064)
			(end 0.7874 0.4064)
			(stroke
				(width 0.1524)
				(type default)
			)
			(layer "F.SilkS")
		)
		(fp_line
			(start -0.67945 0.3048)
			(end -0.67945 -0.305054)
			(stroke
				(width 0.1)
				(type default)
			)
			(layer "F.Fab")
		)
		(fp_line
			(start -0.12065 0.3048)
			(end -0.67945 0.3048)
			(stroke
				(width 0.1)
				(type default)
			)
			(layer "F.Fab")
		)
		(fp_line
			(start 0.120396 0.3048)
			(end 0.120396 0.2794)
			(stroke
				(width 0.1)
				(type default)
			)
			(layer "F.Fab")
		)
		(fp_line
			(start 0.67945 0.3048)
			(end 0.120396 0.3048)
			(stroke
				(width 0.1)
				(type default)
			)
			(layer "F.Fab")
		)
		(fp_line
			(start -0.12065 0.2794)
			(end -0.12065 0.3048)
			(stroke
				(width 0.1)
				(type default)
			)
			(layer "F.Fab")
		)
		(fp_line
			(start 0.120396 0.2794)
			(end -0.12065 0.2794)
			(stroke
				(width 0.1)
				(type default)
			)
			(layer "F.Fab")
		)
		(fp_line
			(start -0.12065 -0.2794)
			(end 0.12065 -0.2794)
			(stroke
				(width 0.1)
				(type default)
			)
			(layer "F.Fab")
		)
		(fp_line
			(start 0.12065 -0.2794)
			(end 0.12065 -0.3048)
			(stroke
				(width 0.1)
				(type default)
			)
			(layer "F.Fab")
		)
		(fp_line
			(start 0.12065 -0.3048)
			(end 0.67945 -0.3048)
			(stroke
				(width 0.1)
				(type default)
			)
			(layer "F.Fab")
		)
		(fp_line
			(start 0.67945 -0.3048)
			(end 0.67945 0.3048)
			(stroke
				(width 0.1)
				(type default)
			)
			(layer "F.Fab")
		)
		(fp_line
			(start -0.67945 -0.305054)
			(end -0.12065 -0.305054)
			(stroke
				(width 0.1)
				(type default)
			)
			(layer "F.Fab")
		)
		(fp_line
			(start -0.12065 -0.305054)
			(end -0.12065 -0.2794)
			(stroke
				(width 0.1)
				(type default)
			)
			(layer "F.Fab")
		)
		(pad "1" smd circle
			(at -0.40005 0 270)
			(size 0 0)
			(layers "F.Cu" "F.Mask" "F.Paste")
			(net "RST_CPU1_DRAM_AB_N")
		)
		(pad "2" smd circle
			(at 0.40005 0 270)
			(size 0 0)
			(layers "F.Cu" "F.Mask" "F.Paste")
			(net "RST_CPU1_DRAM_AB_PLD_N")
		)
	)
	(footprint ""
		(layer "F.Cu")
		(at 186.23788 -99.659948 -90)
		(property "Reference" "R992"
			(at 0 0 270)
			(layer "F.SilkS")
			(hide yes)
			(effects
				(font
					(size 1.27 1.27)
				)
			)
		)
		(property "Value" ""
			(at 0 0 270)
			(layer "F.Fab")
			(effects
				(font
					(size 1.27 1.27)
				)
			)
		)
		(duplicate_pad_numbers_are_jumpers no)
		(fp_line
			(start -0.7874 0.4064)
			(end -0.7874 -0.4064)
			(stroke
				(width 0.1524)
				(type default)
			)
			(layer "F.SilkS")
		)
		(fp_line
			(start 0.7874 0.4064)
			(end -0.7874 0.4064)
			(stroke
				(width 0.1524)
				(type default)
			)
			(layer "F.SilkS")
		)
		(fp_line
			(start -0.7874 -0.4064)
			(end 0.7874 -0.4064)
			(stroke
				(width 0.1524)
				(type default)
			)
			(layer "F.SilkS")
		)
		(fp_line
			(start 0.7874 -0.4064)
			(end 0.7874 0.4064)
			(stroke
				(width 0.1524)
				(type default)
			)
			(layer "F.SilkS")
		)
		(fp_line
			(start -0.67945 0.3048)
			(end -0.67945 -0.305054)
			(stroke
				(width 0.1)
				(type default)
			)
			(layer "F.Fab")
		)
		(fp_line
			(start -0.12065 0.3048)
			(end -0.67945 0.3048)
			(stroke
				(width 0.1)
				(type default)
			)
			(layer "F.Fab")
		)
		(fp_line
			(start 0.120396 0.3048)
			(end 0.120396 0.2794)
			(stroke
				(width 0.1)
				(type default)
			)
			(layer "F.Fab")
		)
		(fp_line
			(start 0.67945 0.3048)
			(end 0.120396 0.3048)
			(stroke
				(width 0.1)
				(type default)
			)
			(layer "F.Fab")
		)
		(fp_line
			(start -0.12065 0.2794)
			(end -0.12065 0.3048)
			(stroke
				(width 0.1)
				(type default)
			)
			(layer "F.Fab")
		)
		(fp_line
			(start 0.120396 0.2794)
			(end -0.12065 0.2794)
			(stroke
				(width 0.1)
				(type default)
			)
			(layer "F.Fab")
		)
		(fp_line
			(start -0.12065 -0.2794)
			(end 0.12065 -0.2794)
			(stroke
				(width 0.1)
				(type default)
			)
			(layer "F.Fab")
		)
		(fp_line
			(start 0.12065 -0.2794)
			(end 0.12065 -0.3048)
			(stroke
				(width 0.1)
				(type default)
			)
			(layer "F.Fab")
		)
		(fp_line
			(start 0.12065 -0.3048)
			(end 0.67945 -0.3048)
			(stroke
				(width 0.1)
				(type default)
			)
			(layer "F.Fab")
		)
		(fp_line
			(start 0.67945 -0.3048)
			(end 0.67945 0.3048)
			(stroke
				(width 0.1)
				(type default)
			)
			(layer "F.Fab")
		)
		(fp_line
			(start -0.67945 -0.305054)
			(end -0.12065 -0.305054)
			(stroke
				(width 0.1)
				(type default)
			)
			(layer "F.Fab")
		)
		(fp_line
			(start -0.12065 -0.305054)
			(end -0.12065 -0.2794)
			(stroke
				(width 0.1)
				(type default)
			)
			(layer "F.Fab")
		)
		(pad "1" smd circle
			(at -0.40005 0 270)
			(size 0 0)
			(layers "F.Cu" "F.Mask" "F.Paste")
			(net "PWRGD_CPU0_LVC1_R")
		)
		(pad "2" smd circle
			(at 0.40005 0 270)
			(size 0 0)
			(layers "F.Cu" "F.Mask" "F.Paste")
			(net "GND")
		)
	)
)
